# T6G (Grand Teton) — schematic netlist excerpt (pin names and nets, part order shuffled) for the footprints in the layout excerpt that follows; sources: Cadence DE-HDL packaged netlist, KiCad conversion of 04192023_DAF0TMB3IC0_F0TG_MB_C_brd_V02_OCP.brd

PC163  Q_CAP  560PF 50V 10% EMPTY  pkg C0402  page 206 : A = SW_PVDDIO_P0_SW4 ; B = SW_PVDDIO_P0_SW4_RC
C917  Q_CAP_DIFFBUS  DIFF BUS_0.22UF 6.3V 20% X6S  pkg C0201  page 63 : \1\ = P5E_CPU0_P0_TX_C_DP<8> ; \2\ = P5E_CPU0_P0_TX_DP<8>
PR3849  Q_RES  17.4K 1% CHIP  pkg 0402LF  page 141 : A = P12V_OCP_IMON_2 ; B = GND

(kicad_pcb
	(version 20260206)
	(generator "pcbnew")
	(generator_version "10.0")
	(general
		(thickness 1.6)
		(legacy_teardrops no)
	)
	(paper "A4")
	(title_block
		(title "04192023_DAF0TMB3IC0_F0TG_MB_C_brd_V02_OCP.brd")
		(comment 1 "Grand Teton / footprints 2507-2509 of 8354")
	)
	(layers
		(0 "F.Cu" signal "TOP")
		(4 "In1.Cu" signal "GND")
		(6 "In2.Cu" signal "IN1")
		(8 "In3.Cu" signal "GND1")
		(10 "In4.Cu" signal "IN2")
		(12 "In5.Cu" signal "GND2")
		(14 "In6.Cu" signal "IN3")
		(16 "In7.Cu" signal "GND3")
		(18 "In8.Cu" signal "VCC")
		(20 "In9.Cu" signal "VCC1")
		(22 "In10.Cu" signal "GND4")
		(24 "In11.Cu" signal "IN4")
		(26 "In12.Cu" signal "GND5")
		(28 "In13.Cu" signal "IN5")
		(30 "In14.Cu" signal "GND6")
		(32 "In15.Cu" signal "IN6")
		(34 "In16.Cu" signal "GND7")
		(2 "B.Cu" signal "BOTTOM")
		(9 "F.Adhes" user "F.Adhesive")
		(11 "B.Adhes" user "B.Adhesive")
		(13 "F.Paste" user "Package Geometry/Pastemask Top")
		(15 "B.Paste" user "Package Geometry/Pastemask Bottom")
		(5 "F.SilkS" user "Ref Des/Silkscreen Top")
		(7 "B.SilkS" user "Ref Des/Silkscreen Bottom")
		(1 "F.Mask" user "Board Geometry/Soldermask Top")
		(3 "B.Mask" user "Board Geometry/Soldermask Bottom")
		(17 "Dwgs.User" user "User.Drawings")
		(19 "Cmts.User" user "User.Comments")
		(21 "Eco1.User" user "User.Eco1")
		(23 "Eco2.User" user "User.Eco2")
		(25 "Edge.Cuts" user "Board Geometry/Outline")
		(27 "Margin" user)
		(31 "F.CrtYd" user "Package Geometry/Place Bound Top")
		(29 "B.CrtYd" user "Package Geometry/Place Bound Bottom")
		(35 "F.Fab" user "Ref Des/Assembly Top")
		(33 "B.Fab" user "Ref Des/Assembly Bottom")
	)
	(footprint ""
		(layer "F.Cu")
		(at 271.728184 -343.712038 180)
		(property "Reference" "PC163"
			(at 0 0 180)
			(layer "F.SilkS")
			(hide yes)
			(effects
				(font
					(size 1.27 1.27)
				)
			)
		)
		(property "Value" ""
			(at 0 0 180)
			(layer "F.Fab")
			(effects
				(font
					(size 1.27 1.27)
				)
			)
		)
		(duplicate_pad_numbers_are_jumpers no)
		(fp_line
			(start 0.7874 0.4064)
			(end -0.7874 0.4064)
			(stroke
				(width 0.1524)
				(type default)
			)
			(layer "F.SilkS")
		)
		(fp_line
			(start 0.7874 -0.4064)
			(end 0.7874 0.4064)
			(stroke
				(width 0.1524)
				(type default)
			)
			(layer "F.SilkS")
		)
		(fp_line
			(start -0.7874 0.4064)
			(end -0.7874 -0.4064)
			(stroke
				(width 0.1524)
				(type default)
			)
			(layer "F.SilkS")
		)
		(fp_line
			(start -0.7874 -0.4064)
			(end 0.7874 -0.4064)
			(stroke
				(width 0.1524)
				(type default)
			)
			(layer "F.SilkS")
		)
		(fp_line
			(start 0.67945 0.3048)
			(end 0.120396 0.3048)
			(stroke
				(width 0.1)
				(type default)
			)
			(layer "F.Fab")
		)
		(fp_line
			(start 0.67945 -0.3048)
			(end 0.67945 0.3048)
			(stroke
				(width 0.1)
				(type default)
			)
			(layer "F.Fab")
		)
		(fp_line
			(start 0.12065 -0.2794)
			(end 0.12065 -0.3048)
			(stroke
				(width 0.1)
				(type default)
			)
			(layer "F.Fab")
		)
		(fp_line
			(start 0.12065 -0.3048)
			(end 0.67945 -0.3048)
			(stroke
				(width 0.1)
				(type default)
			)
			(layer "F.Fab")
		)
		(fp_line
			(start 0.120396 0.3048)
			(end 0.120396 0.2794)
			(stroke
				(width 0.1)
				(type default)
			)
			(layer "F.Fab")
		)
		(fp_line
			(start 0.120396 0.2794)
			(end -0.12065 0.2794)
			(stroke
				(width 0.1)
				(type default)
			)
			(layer "F.Fab")
		)
		(fp_line
			(start -0.12065 0.3048)
			(end -0.67945 0.3048)
			(stroke
				(width 0.1)
				(type default)
			)
			(layer "F.Fab")
		)
		(fp_line
			(start -0.12065 0.2794)
			(end -0.12065 0.3048)
			(stroke
				(width 0.1)
				(type default)
			)
			(layer "F.Fab")
		)
		(fp_line
			(start -0.12065 -0.2794)
			(end 0.12065 -0.2794)
			(stroke
				(width 0.1)
				(type default)
			)
			(layer "F.Fab")
		)
		(fp_line
			(start -0.12065 -0.305054)
			(end -0.12065 -0.2794)
			(stroke
				(width 0.1)
				(type default)
			)
			(layer "F.Fab")
		)
		(fp_line
			(start -0.67945 0.3048)
			(end -0.67945 -0.305054)
			(stroke
				(width 0.1)
				(type default)
			)
			(layer "F.Fab")
		)
		(fp_line
			(start -0.67945 -0.305054)
			(end -0.12065 -0.305054)
			(stroke
				(width 0.1)
				(type default)
			)
			(layer "F.Fab")
		)
		(pad "1" smd circle
			(at -0.40005 0 180)
			(size 0 0)
			(layers "F.Cu" "F.Mask" "F.Paste")
			(net "SW_PVDDIO_P0_SW4")
		)
		(pad "2" smd circle
			(at 0.40005 0 180)
			(size 0 0)
			(layers "F.Cu" "F.Mask" "F.Paste")
			(net "SW_PVDDIO_P0_SW4_RC")
		)
	)
	(footprint ""
		(layer "F.Cu")
		(at 312.603896 -381.41783 -90)
		(property "Reference" "C917"
			(at 0 0 270)
			(layer "F.SilkS")
			(hide yes)
			(effects
				(font
					(size 1.27 1.27)
				)
			)
		)
		(property "Value" ""
			(at 0 0 270)
			(layer "F.Fab")
			(effects
				(font
					(size 1.27 1.27)
				)
			)
		)
		(duplicate_pad_numbers_are_jumpers no)
		(fp_line
			(start -0.299974 0.150114)
			(end -0.299974 -0.150114)
			(stroke
				(width 0.1)
				(type default)
			)
			(layer "F.Fab")
		)
		(fp_line
			(start 0.299974 0.150114)
			(end -0.299974 0.150114)
			(stroke
				(width 0.1)
				(type default)
			)
			(layer "F.Fab")
		)
		(fp_line
			(start -0.299974 -0.150114)
			(end 0.299974 -0.150114)
			(stroke
				(width 0.1)
				(type default)
			)
			(layer "F.Fab")
		)
		(fp_line
			(start 0.299974 -0.150114)
			(end 0.299974 0.150114)
			(stroke
				(width 0.1)
				(type default)
			)
			(layer "F.Fab")
		)
		(pad "1" smd rect
			(at -0.2667 0 270)
			(size 0.3048 0.381)
			(layers "F.Cu" "F.Mask" "F.Paste")
			(net "P5E_CPU0_P0_TX_C_DP<8>")
		)
		(pad "2" smd rect
			(at 0.2667 0 270)
			(size 0.3048 0.381)
			(layers "F.Cu" "F.Mask" "F.Paste")
			(net "P5E_CPU0_P0_TX_DP<8>")
		)
	)
	(footprint ""
		(layer "F.Cu")
		(at 63.575438 -31.887922 90)
		(property "Reference" "PR3849"
			(at 0 0 90)
			(layer "F.SilkS")
			(hide yes)
			(effects
				(font
					(size 1.27 1.27)
				)
			)
		)
		(property "Value" ""
			(at 0 0 90)
			(layer "F.Fab")
			(effects
				(font
					(size 1.27 1.27)
				)
			)
		)
		(duplicate_pad_numbers_are_jumpers no)
		(fp_line
			(start 0.7874 -0.4064)
			(end 0.7874 0.4064)
			(stroke
				(width 0.1524)
				(type default)
			)
			(layer "F.SilkS")
		)
		(fp_line
			(start -0.7874 -0.4064)
			(end 0.7874 -0.4064)
			(stroke
				(width 0.1524)
				(type default)
			)
			(layer "F.SilkS")
		)
		(fp_line
			(start 0.7874 0.4064)
			(end -0.7874 0.4064)
			(stroke
				(width 0.1524)
				(type default)
			)
			(layer "F.SilkS")
		)
		(fp_line
			(start -0.7874 0.4064)
			(end -0.7874 -0.4064)
			(stroke
				(width 0.1524)
				(type default)
			)
			(layer "F.SilkS")
		)
		(fp_line
			(start -0.12065 -0.305054)
			(end -0.12065 -0.2794)
			(stroke
				(width 0.1)
				(type default)
			)
			(layer "F.Fab")
		)
		(fp_line
			(start -0.67945 -0.305054)
			(end -0.12065 -0.305054)
			(stroke
				(width 0.1)
				(type default)
			)
			(layer "F.Fab")
		)
		(fp_line
			(start 0.67945 -0.3048)
			(end 0.67945 0.3048)
			(stroke
				(width 0.1)
				(type default)
			)
			(layer "F.Fab")
		)
		(fp_line
			(start 0.12065 -0.3048)
			(end 0.67945 -0.3048)
			(stroke
				(width 0.1)
				(type default)
			)
			(layer "F.Fab")
		)
		(fp_line
			(start 0.12065 -0.2794)
			(end 0.12065 -0.3048)
			(stroke
				(width 0.1)
				(type default)
			)
			(layer "F.Fab")
		)
		(fp_line
			(start -0.12065 -0.2794)
			(end 0.12065 -0.2794)
			(stroke
				(width 0.1)
				(type default)
			)
			(layer "F.Fab")
		)
		(fp_line
			(start 0.120396 0.2794)
			(end -0.12065 0.2794)
			(stroke
				(width 0.1)
				(type default)
			)
			(layer "F.Fab")
		)
		(fp_line
			(start -0.12065 0.2794)
			(end -0.12065 0.3048)
			(stroke
				(width 0.1)
				(type default)
			)
			(layer "F.Fab")
		)
		(fp_line
			(start 0.67945 0.3048)
			(end 0.120396 0.3048)
			(stroke
				(width 0.1)
				(type default)
			)
			(layer "F.Fab")
		)
		(fp_line
			(start 0.120396 0.3048)
			(end 0.120396 0.2794)
			(stroke
				(width 0.1)
				(type default)
			)
			(layer "F.Fab")
		)
		(fp_line
			(start -0.12065 0.3048)
			(end -0.67945 0.3048)
			(stroke
				(width 0.1)
				(type default)
			)
			(layer "F.Fab")
		)
		(fp_line
			(start -0.67945 0.3048)
			(end -0.67945 -0.305054)
			(stroke
				(width 0.1)
				(type default)
			)
			(layer "F.Fab")
		)
		(pad "1" smd circle
			(at -0.40005 0 90)
			(size 0 0)
			(layers "F.Cu" "F.Mask" "F.Paste")
			(net "P12V_OCP_IMON_2")
		)
		(pad "2" smd circle
			(at 0.40005 0 90)
			(size 0 0)
			(layers "F.Cu" "F.Mask" "F.Paste")
			(net "GND")
		)
	)
)
